(kicad_pcb
	(version 20260206)
	(generator "pcbnew")
	(generator_version "10.0")
	(general
		(thickness 1.6)
		(legacy_teardrops no)
	)
	(paper "A4")
	(title_block
		(title "Bryce Canyon_IOM_IOC_16318-2_OCP.brd")
		(comment 1 "Bryce Canyon / footprints 685-692 of 1605")
	)
	(layers
		(0 "F.Cu" signal "TOP")
		(4 "In1.Cu" signal "L2GND")
		(6 "In2.Cu" signal "L3")
		(8 "In3.Cu" signal "L4VCC")
		(10 "In4.Cu" signal "L5VCC")
		(12 "In5.Cu" signal "L6")
		(14 "In6.Cu" signal "L7GND")
		(2 "B.Cu" signal "BOTTOM")
		(9 "F.Adhes" user "F.Adhesive")
		(11 "B.Adhes" user "B.Adhesive")
		(13 "F.Paste" user "Package Geometry/Pastemask Top")
		(15 "B.Paste" user "Package Geometry/Pastemask Bottom")
		(5 "F.SilkS" user "Ref Des/Silkscreen Top")
		(7 "B.SilkS" user "Ref Des/Silkscreen Bottom")
		(1 "F.Mask" user "Board Geometry/Soldermask Top")
		(3 "B.Mask" user "Board Geometry/Soldermask Bottom")
		(17 "Dwgs.User" user "User.Drawings")
		(19 "Cmts.User" user "User.Comments")
		(21 "Eco1.User" user "User.Eco1")
		(23 "Eco2.User" user "User.Eco2")
		(25 "Edge.Cuts" user "Board Geometry/Outline")
		(27 "Margin" user)
		(31 "F.CrtYd" user "Package Geometry/Place Bound Top")
		(29 "B.CrtYd" user "Package Geometry/Place Bound Bottom")
		(35 "F.Fab" user "Ref Des/Assembly Top")
		(33 "B.Fab" user "Ref Des/Assembly Bottom")
	)
	(footprint ""
		(layer "F.Cu")
		(at 78.122018 -83.779868 90)
		(property "Reference" "VIA5"
			(at 0 0 90)
			(layer "F.SilkS")
			(hide yes)
			(effects
				(font
					(size 1.27 1.27)
				)
			)
		)
		(property "Value" "85OHM-8L-1D6MM-L16L18-GP"
			(at 4.064 0.6096 90)
			(unlocked yes)
			(layer "F.Fab")
			(hide yes)
			(effects
				(font
					(size 1.016 1.016)
					(thickness 0.1524)
				)
			)
		)
		(property "Device Type" "VIA-PCIE-4P-368076"
			(at 4.064 -0.9144 90)
			(unlocked yes)
			(layer "F.Fab")
			(hide yes)
			(effects
				(font
					(size 1.016 1.016)
					(thickness 0.1524)
				)
			)
		)
		(duplicate_pad_numbers_are_jumpers no)
		(fp_rect
			(start -1.8415 0.381)
			(end 1.8415 -0.381)
			(stroke
				(width 0)
				(type default)
			)
			(fill no)
			(layer "F.CrtYd")
		)
		(fp_rect
			(start -1.8415 0.381)
			(end 1.8415 -0.381)
			(stroke
				(width 0)
				(type default)
			)
			(fill no)
			(layer "F.Fab")
		)
		(pad "1" thru_hole circle
			(at -1.4605 0 90)
			(size 0.508 0.508)
			(drill 0.254)
			(layers "*.Cu" "*.Mask")
			(remove_unused_layers no)
			(net "GND")
			(clearance 0.127)
			(thermal_gap 0.127)
		)
		(pad "2" thru_hole circle
			(at -0.4445 0 90)
			(size 0.508 0.508)
			(drill 0.254)
			(layers "*.Cu" "*.Mask")
			(remove_unused_layers no)
			(net "PCIE_COMP_TO_IOM_20_DP")
			(clearance 0.127)
			(thermal_gap 0.127)
		)
		(pad "3" thru_hole circle
			(at 0.4445 0 90)
			(size 0.508 0.508)
			(drill 0.254)
			(layers "*.Cu" "*.Mask")
			(remove_unused_layers no)
			(net "PCIE_COMP_TO_IOM_20_DN")
			(clearance 0.127)
			(thermal_gap 0.127)
		)
		(pad "4" thru_hole circle
			(at 1.4605 0 90)
			(size 0.508 0.508)
			(drill 0.254)
			(layers "*.Cu" "*.Mask")
			(remove_unused_layers no)
			(net "GND")
			(clearance 0.127)
			(thermal_gap 0.127)
		)
	)
	(footprint ""
		(layer "F.Cu")
		(at 34.2138 -176.8094 180)
		(property "Reference" "G3"
			(at 0 0 180)
			(layer "F.SilkS")
			(hide yes)
			(effects
				(font
					(size 1.27 1.27)
				)
			)
		)
		(property "Value" "COPPER-CLOSE-GP-U"
			(at 0.0762 -2.8702 180)
			(unlocked yes)
			(layer "F.Fab")
			(hide yes)
			(effects
				(font
					(size 1.016 1.016)
					(thickness 0.1524)
				)
			)
		)
		(property "Device Type" "CON2C-U"
			(at 0.0762 -4.3942 180)
			(unlocked yes)
			(layer "F.Fab")
			(hide yes)
			(effects
				(font
					(size 1.016 1.016)
					(thickness 0.1524)
				)
			)
		)
		(duplicate_pad_numbers_are_jumpers no)
		(fp_rect
			(start -0.9398 0.9652)
			(end 0.9398 -0.9652)
			(stroke
				(width 0)
				(type default)
			)
			(fill no)
			(layer "F.CrtYd")
		)
		(fp_rect
			(start -0.9398 0.9652)
			(end 0.9398 -0.9652)
			(stroke
				(width 0)
				(type default)
			)
			(fill no)
			(layer "F.Fab")
		)
		(pad "1" smd custom
			(at 0 -0.5334 180)
			(size 0.17145 0.17145)
			(layers "F.Cu" "F.Mask" "F.Paste")
			(net "AGND_P3V3_STBY")
			(options
				(clearance outline)
				(anchor circle)
			)
			(primitives
				(gr_poly
					(pts
						(xy -0.127 0.3429) (xy -0.127 0.1651) (xy -0.635 -0.3429) (xy 0.635 -0.3429) (xy 0.127 0.1651)
						(xy 0.127 0.3429)
					)
					(width 0)
					(fill yes)
				)
			)
		)
		(pad "2" smd custom
			(at 0 0.5334 180)
			(size 0.17145 0.17145)
			(layers "F.Cu" "F.Mask" "F.Paste")
			(net "GND")
			(options
				(clearance outline)
				(anchor circle)
			)
			(primitives
				(gr_poly
					(pts
						(xy -0.635 0.3429) (xy -0.127 -0.1651) (xy -0.127 -0.3429) (xy 0.127 -0.3429) (xy 0.127 -0.1651)
						(xy 0.635 0.3429)
					)
					(width 0)
					(fill yes)
				)
			)
		)
	)
	(footprint ""
		(layer "F.Cu")
		(at 184.404 -81.788 90)
		(property "Reference" "TP98"
			(at 0 0 90)
			(layer "F.SilkS")
			(hide yes)
			(effects
				(font
					(size 1.27 1.27)
				)
			)
		)
		(property "Value" "TPAD28-2-GP"
			(at -0.0127 -1.6637 90)
			(unlocked yes)
			(layer "F.Fab")
			(hide yes)
			(effects
				(font
					(size 1.016 1.016)
					(thickness 0.1524)
				)
			)
		)
		(property "Device Type" "TPAD28"
			(at -0.0127 -3.1877 90)
			(unlocked yes)
			(layer "F.Fab")
			(hide yes)
			(effects
				(font
					(size 1.016 1.016)
					(thickness 0.1524)
				)
			)
		)
		(duplicate_pad_numbers_are_jumpers no)
		(fp_poly
			(pts
				(arc
					(start 0 0.3556)
					(mid 0 -0.3556)
					(end 0 0.3556)
				)
			)
			(stroke
				(width 0)
				(type default)
			)
			(fill no)
			(layer "F.CrtYd")
		)
		(fp_poly
			(pts
				(arc
					(start 0 0.6096)
					(mid 0 -0.6096)
					(end 0 0.6096)
				)
			)
			(stroke
				(width 0)
				(type default)
			)
			(fill no)
			(layer "F.Fab")
		)
		(pad "1" smd circle
			(at 0 0 90)
			(size 0.7112 0.7112)
			(layers "F.Cu" "F.Mask" "F.Paste")
			(net "IOC_GPIO_13")
		)
	)
	(footprint ""
		(layer "F.Cu")
		(at 57.3786 -158.8516)
		(property "Reference" "R390"
			(at 0 0 0)
			(layer "F.SilkS")
			(hide yes)
			(effects
				(font
					(size 1.27 1.27)
				)
			)
		)
		(property "Value" "4K7R2F-GP"
			(at 0.064008 -3.993896 0)
			(unlocked yes)
			(layer "F.Fab")
			(hide yes)
			(effects
				(font
					(size 1.016 1.016)
					(thickness 0.1524)
				)
			)
		)
		(property "Device Type" "R402H16"
			(at 0.064008 -5.517896 0)
			(unlocked yes)
			(layer "F.Fab")
			(hide yes)
			(effects
				(font
					(size 1.016 1.016)
					(thickness 0.1524)
				)
			)
		)
		(duplicate_pad_numbers_are_jumpers no)
		(fp_line
			(start -0.508 -0.9398)
			(end -0.508 0.9398)
			(stroke
				(width 0.1524)
				(type default)
			)
			(layer "F.SilkS")
		)
		(fp_line
			(start 0.508 -0.9398)
			(end -0.508 -0.9398)
			(stroke
				(width 0.1524)
				(type default)
			)
			(layer "F.SilkS")
		)
		(fp_rect
			(start -0.508 0.9398)
			(end 0.508 -0.9398)
			(stroke
				(width 0)
				(type default)
			)
			(fill no)
			(layer "F.CrtYd")
		)
		(fp_rect
			(start -0.508 0.9398)
			(end 0.508 -0.9398)
			(stroke
				(width 0)
				(type default)
			)
			(fill no)
			(layer "F.Fab")
		)
		(pad "1" smd custom
			(at 0 -0.4445)
			(size 0.1397 0.1397)
			(layers "F.Cu" "F.Mask" "F.Paste")
			(net "P3V3_STBY")
			(options
				(clearance outline)
				(anchor circle)
			)
			(primitives
				(gr_poly
					(pts
						(arc
							(start -0.1778 -0.2794)
							(mid -0.249642 -0.249642)
							(end -0.2794 -0.1778)
						)
						(arc
							(start -0.2794 0.1778)
							(mid -0.249642 0.249642)
							(end -0.1778 0.2794)
						)
						(arc
							(start 0.1778 0.2794)
							(mid 0.249642 0.249642)
							(end 0.2794 0.1778)
						)
						(arc
							(start 0.2794 -0.1778)
							(mid 0.249642 -0.249642)
							(end 0.1778 -0.2794)
						)
					)
					(width 0)
					(fill yes)
				)
			)
		)
		(pad "2" smd custom
			(at 0 0.4445)
			(size 0.1397 0.1397)
			(layers "F.Cu" "F.Mask" "F.Paste")
			(net "MAC2_TXCTL")
			(options
				(clearance outline)
				(anchor circle)
			)
			(primitives
				(gr_poly
					(pts
						(arc
							(start -0.1778 -0.2794)
							(mid -0.249642 -0.249642)
							(end -0.2794 -0.1778)
						)
						(arc
							(start -0.2794 0.1778)
							(mid -0.249642 0.249642)
							(end -0.1778 0.2794)
						)
						(arc
							(start 0.1778 0.2794)
							(mid 0.249642 0.249642)
							(end 0.2794 0.1778)
						)
						(arc
							(start 0.2794 -0.1778)
							(mid 0.249642 -0.249642)
							(end 0.1778 -0.2794)
						)
					)
					(width 0)
					(fill yes)
				)
			)
		)
	)
	(footprint ""
		(layer "F.Cu")
		(at 194.991736 -134.1755 180)
		(property "Reference" "Q9"
			(at 0 0 180)
			(layer "F.SilkS")
			(hide yes)
			(effects
				(font
					(size 1.27 1.27)
				)
			)
		)
		(property "Value" "SSM3K324R-GP"
			(at 0.127 -8.9662 180)
			(unlocked yes)
			(layer "F.Fab")
			(hide yes)
			(effects
				(font
					(size 1.016 1.016)
					(thickness 0.1524)
				)
			)
		)
		(property "Device Type" "SOT23DGS2D4H35"
			(at 0.127 -10.4902 180)
			(unlocked yes)
			(layer "F.Fab")
			(hide yes)
			(effects
				(font
					(size 1.016 1.016)
					(thickness 0.1524)
				)
			)
		)
		(duplicate_pad_numbers_are_jumpers no)
		(fp_line
			(start 1.651 1.778)
			(end 1.651 -1.778)
			(stroke
				(width 0.1524)
				(type default)
			)
			(layer "F.SilkS")
		)
		(fp_line
			(start 1.651 -1.778)
			(end -1.651 -1.778)
			(stroke
				(width 0.1524)
				(type default)
			)
			(layer "F.SilkS")
		)
		(fp_line
			(start -1.651 1.778)
			(end 1.651 1.778)
			(stroke
				(width 0.1524)
				(type default)
			)
			(layer "F.SilkS")
		)
		(fp_line
			(start -1.651 -1.778)
			(end -1.651 1.778)
			(stroke
				(width 0.1524)
				(type default)
			)
			(layer "F.SilkS")
		)
		(fp_poly
			(pts
				(xy -1.778 1.8796) (xy -1.778 -1.8796) (xy 1.778 -1.8796) (xy 1.778 1.8796)
			)
			(stroke
				(width 0)
				(type default)
			)
			(fill no)
			(layer "F.CrtYd")
		)
		(fp_poly
			(pts
				(xy -1.778 1.8796) (xy -1.778 -1.8796) (xy 1.778 -1.8796) (xy 1.778 1.8796)
			)
			(stroke
				(width 0)
				(type default)
			)
			(fill no)
			(layer "F.Fab")
		)
		(pad "D" smd custom
			(at 0 -0.9525 180)
			(size 0.1905 0.1905)
			(layers "F.Cu" "F.Mask" "F.Paste")
			(net "Q8_G")
			(options
				(clearance outline)
				(anchor circle)
			)
			(primitives
				(gr_poly
					(pts
						(arc
							(start -0.1778 0.5715)
							(mid -0.321484 0.511984)
							(end -0.381 0.3683)
						)
						(arc
							(start -0.381 -0.3683)
							(mid -0.321484 -0.511984)
							(end -0.1778 -0.5715)
						)
						(arc
							(start 0.1778 -0.5715)
							(mid 0.321484 -0.511984)
							(end 0.381 -0.3683)
						)
						(arc
							(start 0.381 0.3683)
							(mid 0.321484 0.511984)
							(end 0.1778 0.5715)
						)
					)
					(width 0)
					(fill yes)
				)
			)
		)
		(pad "G" smd custom
			(at -0.98425 0.9525 180)
			(size 0.1905 0.1905)
			(layers "F.Cu" "F.Mask" "F.Paste")
			(net "Q9_G")
			(options
				(clearance outline)
				(anchor circle)
			)
			(primitives
				(gr_poly
					(pts
						(arc
							(start -0.1778 0.5715)
							(mid -0.321484 0.511984)
							(end -0.381 0.3683)
						)
						(arc
							(start -0.381 -0.3683)
							(mid -0.321484 -0.511984)
							(end -0.1778 -0.5715)
						)
						(arc
							(start 0.1778 -0.5715)
							(mid 0.321484 -0.511984)
							(end 0.381 -0.3683)
						)
						(arc
							(start 0.381 0.3683)
							(mid 0.321484 0.511984)
							(end 0.1778 0.5715)
						)
					)
					(width 0)
					(fill yes)
				)
			)
		)
		(pad "S" smd custom
			(at 0.98425 0.9525 180)
			(size 0.1905 0.1905)
			(layers "F.Cu" "F.Mask" "F.Paste")
			(net "GND")
			(options
				(clearance outline)
				(anchor circle)
			)
			(primitives
				(gr_poly
					(pts
						(arc
							(start -0.1778 0.5715)
							(mid -0.321484 0.511984)
							(end -0.381 0.3683)
						)
						(arc
							(start -0.381 -0.3683)
							(mid -0.321484 -0.511984)
							(end -0.1778 -0.5715)
						)
						(arc
							(start 0.1778 -0.5715)
							(mid 0.321484 -0.511984)
							(end 0.381 -0.3683)
						)
						(arc
							(start 0.381 0.3683)
							(mid 0.321484 0.511984)
							(end 0.1778 0.5715)
						)
					)
					(width 0)
					(fill yes)
				)
			)
		)
	)
	(footprint ""
		(layer "F.Cu")
		(at 163.23564 -143.520922)
		(property "Reference" "R514"
			(at 0 0 0)
			(layer "F.SilkS")
			(hide yes)
			(effects
				(font
					(size 1.27 1.27)
				)
			)
		)
		(property "Value" "10R3F-GP"
			(at -0.0254 -2.5146 0)
			(unlocked yes)
			(layer "F.Fab")
			(hide yes)
			(effects
				(font
					(size 1.016 1.016)
					(thickness 0.1524)
				)
			)
		)
		(property "Device Type" "R603H22"
			(at -0.0254 -4.0386 0)
			(unlocked yes)
			(layer "F.Fab")
			(hide yes)
			(effects
				(font
					(size 1.016 1.016)
					(thickness 0.1524)
				)
			)
		)
		(duplicate_pad_numbers_are_jumpers no)
		(fp_line
			(start -0.4826 0)
			(end -0.2032 0)
			(stroke
				(width 0.2032)
				(type default)
			)
			(layer "F.SilkS")
		)
		(fp_line
			(start 0.2032 0)
			(end 0.4826 0)
			(stroke
				(width 0.2032)
				(type default)
			)
			(layer "F.SilkS")
		)
		(fp_rect
			(start -0.5842 1.3335)
			(end 0.5842 -1.3335)
			(stroke
				(width 0)
				(type default)
			)
			(fill no)
			(layer "F.CrtYd")
		)
		(fp_rect
			(start -0.5842 1.3335)
			(end 0.5842 -1.3335)
			(stroke
				(width 0)
				(type default)
			)
			(fill no)
			(layer "F.Fab")
		)
		(pad "1" smd custom
			(at 0 -0.762)
			(size 0.2159 0.2159)
			(layers "F.Cu" "F.Mask" "F.Paste")
			(net "P1V8_STBY_CC")
			(options
				(clearance outline)
				(anchor circle)
			)
			(primitives
				(gr_poly
					(pts
						(arc
							(start -0.3302 -0.4318)
							(mid -0.402042 -0.402042)
							(end -0.4318 -0.3302)
						)
						(arc
							(start -0.4318 0.3302)
							(mid -0.402042 0.402042)
							(end -0.3302 0.4318)
						)
						(arc
							(start 0.3302 0.4318)
							(mid 0.402042 0.402042)
							(end 0.4318 0.3302)
						)
						(arc
							(start 0.4318 -0.3302)
							(mid 0.402042 -0.402042)
							(end 0.3302 -0.4318)
						)
					)
					(width 0)
					(fill yes)
				)
			)
		)
		(pad "2" smd custom
			(at 0 0.762)
			(size 0.2159 0.2159)
			(layers "F.Cu" "F.Mask" "F.Paste")
			(net "P1V8_STBY_CC_R")
			(options
				(clearance outline)
				(anchor circle)
			)
			(primitives
				(gr_poly
					(pts
						(arc
							(start -0.3302 -0.4318)
							(mid -0.402042 -0.402042)
							(end -0.4318 -0.3302)
						)
						(arc
							(start -0.4318 0.3302)
							(mid -0.402042 0.402042)
							(end -0.3302 0.4318)
						)
						(arc
							(start 0.3302 0.4318)
							(mid 0.402042 0.402042)
							(end 0.4318 0.3302)
						)
						(arc
							(start 0.4318 -0.3302)
							(mid 0.402042 -0.402042)
							(end 0.3302 -0.4318)
						)
					)
					(width 0)
					(fill yes)
				)
			)
		)
	)
	(footprint ""
		(layer "F.Cu")
		(at 184.658 -88.392 180)
		(property "Reference" "R653"
			(at 0 0 180)
			(layer "F.SilkS")
			(hide yes)
			(effects
				(font
					(size 1.27 1.27)
				)
			)
		)
		(property "Value" "10KR2F-2-GP"
			(at 0.064008 -3.993896 180)
			(unlocked yes)
			(layer "F.Fab")
			(hide yes)
			(effects
				(font
					(size 1.016 1.016)
					(thickness 0.1524)
				)
			)
		)
		(property "Device Type" "R402H16"
			(at 0.064008 -5.517896 180)
			(unlocked yes)
			(layer "F.Fab")
			(hide yes)
			(effects
				(font
					(size 1.016 1.016)
					(thickness 0.1524)
				)
			)
		)
		(duplicate_pad_numbers_are_jumpers no)
		(fp_line
			(start 0.508 -0.9398)
			(end -0.508 -0.9398)
			(stroke
				(width 0.1524)
				(type default)
			)
			(layer "F.SilkS")
		)
		(fp_line
			(start -0.508 -0.9398)
			(end -0.508 0.9398)
			(stroke
				(width 0.1524)
				(type default)
			)
			(layer "F.SilkS")
		)
		(fp_rect
			(start -0.508 0.9398)
			(end 0.508 -0.9398)
			(stroke
				(width 0)
				(type default)
			)
			(fill no)
			(layer "F.CrtYd")
		)
		(fp_rect
			(start -0.508 0.9398)
			(end 0.508 -0.9398)
			(stroke
				(width 0)
				(type default)
			)
			(fill no)
			(layer "F.Fab")
		)
		(pad "1" smd custom
			(at 0 -0.4445 180)
			(size 0.1397 0.1397)
			(layers "F.Cu" "F.Mask" "F.Paste")
			(net "SYS_DBMODE3")
			(options
				(clearance outline)
				(anchor circle)
			)
			(primitives
				(gr_poly
					(pts
						(arc
							(start -0.1778 -0.2794)
							(mid -0.249642 -0.249642)
							(end -0.2794 -0.1778)
						)
						(arc
							(start -0.2794 0.1778)
							(mid -0.249642 0.249642)
							(end -0.1778 0.2794)
						)
						(arc
							(start 0.1778 0.2794)
							(mid 0.249642 0.249642)
							(end 0.2794 0.1778)
						)
						(arc
							(start 0.2794 -0.1778)
							(mid 0.249642 -0.249642)
							(end 0.1778 -0.2794)
						)
					)
					(width 0)
					(fill yes)
				)
			)
		)
		(pad "2" smd custom
			(at 0 0.4445 180)
			(size 0.1397 0.1397)
			(layers "F.Cu" "F.Mask" "F.Paste")
			(net "GND")
			(options
				(clearance outline)
				(anchor circle)
			)
			(primitives
				(gr_poly
					(pts
						(arc
							(start -0.1778 -0.2794)
							(mid -0.249642 -0.249642)
							(end -0.2794 -0.1778)
						)
						(arc
							(start -0.2794 0.1778)
							(mid -0.249642 0.249642)
							(end -0.1778 0.2794)
						)
						(arc
							(start 0.1778 0.2794)
							(mid 0.249642 0.249642)
							(end 0.2794 0.1778)
						)
						(arc
							(start 0.2794 -0.1778)
							(mid 0.249642 -0.249642)
							(end 0.1778 -0.2794)
						)
					)
					(width 0)
					(fill yes)
				)
			)
		)
	)
	(footprint ""
		(layer "F.Cu")
		(at 20.582128 -131.007358 180)
		(property "Reference" "R226"
			(at 0 0 180)
			(layer "F.SilkS")
			(hide yes)
			(effects
				(font
					(size 1.27 1.27)
				)
			)
		)
		(property "Value" "120R2F-GP"
			(at 0.064008 -3.993896 180)
			(unlocked yes)
			(layer "F.Fab")
			(hide yes)
			(effects
				(font
					(size 1.016 1.016)
					(thickness 0.1524)
				)
			)
		)
		(property "Device Type" "R402H16"
			(at 0.064008 -5.517896 180)
			(unlocked yes)
			(layer "F.Fab")
			(hide yes)
			(effects
				(font
					(size 1.016 1.016)
					(thickness 0.1524)
				)
			)
		)
		(duplicate_pad_numbers_are_jumpers no)
		(fp_line
			(start 0.508 -0.9398)
			(end -0.508 -0.9398)
			(stroke
				(width 0.1524)
				(type default)
			)
			(layer "F.SilkS")
		)
		(fp_line
			(start -0.508 -0.9398)
			(end -0.508 0.9398)
			(stroke
				(width 0.1524)
				(type default)
			)
			(layer "F.SilkS")
		)
		(fp_rect
			(start -0.508 0.9398)
			(end 0.508 -0.9398)
			(stroke
				(width 0)
				(type default)
			)
			(fill no)
			(layer "F.CrtYd")
		)
		(fp_rect
			(start -0.508 0.9398)
			(end 0.508 -0.9398)
			(stroke
				(width 0)
				(type default)
			)
			(fill no)
			(layer "F.Fab")
		)
		(pad "1" smd custom
			(at 0 -0.4445 180)
			(size 0.1397 0.1397)
			(layers "F.Cu" "F.Mask" "F.Paste")
			(net "MEMCASN")
			(options
				(clearance outline)
				(anchor circle)
			)
			(primitives
				(gr_poly
					(pts
						(arc
							(start -0.1778 -0.2794)
							(mid -0.249642 -0.249642)
							(end -0.2794 -0.1778)
						)
						(arc
							(start -0.2794 0.1778)
							(mid -0.249642 0.249642)
							(end -0.1778 0.2794)
						)
						(arc
							(start 0.1778 0.2794)
							(mid 0.249642 0.249642)
							(end 0.2794 0.1778)
						)
						(arc
							(start 0.2794 -0.1778)
							(mid 0.249642 -0.249642)
							(end 0.1778 -0.2794)
						)
					)
					(width 0)
					(fill yes)
				)
			)
		)
		(pad "2" smd custom
			(at 0 0.4445 180)
			(size 0.1397 0.1397)
			(layers "F.Cu" "F.Mask" "F.Paste")
			(net "P1V2_STBY")
			(options
				(clearance outline)
				(anchor circle)
			)
			(primitives
				(gr_poly
					(pts
						(arc
							(start -0.1778 -0.2794)
							(mid -0.249642 -0.249642)
							(end -0.2794 -0.1778)
						)
						(arc
							(start -0.2794 0.1778)
							(mid -0.249642 0.249642)
							(end -0.1778 0.2794)
						)
						(arc
							(start 0.1778 0.2794)
							(mid 0.249642 0.249642)
							(end 0.2794 0.1778)
						)
						(arc
							(start 0.2794 -0.1778)
							(mid 0.249642 -0.249642)
							(end 0.1778 -0.2794)
						)
					)
					(width 0)
					(fill yes)
				)
			)
		)
	)
)
